(kicad_pcb
	(version 20221018)
	(generator pcbnew)
	(general
    (thickness 1.62)
  )
	(paper "A4")
	(title_block
    (title "ECP5 - Datacenter Secure Control Module (DC-SCM)")
    (date "2024-07-01")
    (rev "1.2.1")
		(comment 9 "footprints 191-195 of 506")
	)
	(layers
    (0 "F.Cu" signal)
    (1 "In1.Cu" power)
    (2 "In2.Cu" signal)
    (3 "In3.Cu" power)
    (4 "In4.Cu" power)
    (5 "In5.Cu" signal)
    (6 "In6.Cu" power)
    (31 "B.Cu" signal)
    (32 "B.Adhes" user "B.Adhesive")
    (33 "F.Adhes" user "F.Adhesive")
    (34 "B.Paste" user)
    (35 "F.Paste" user)
    (36 "B.SilkS" user "B.Silkscreen")
    (37 "F.SilkS" user "F.Silkscreen")
    (38 "B.Mask" user)
    (39 "F.Mask" user)
    (40 "Dwgs.User" user "User.Drawings")
    (41 "Cmts.User" user "User.Comments")
    (42 "Eco1.User" user "User.Eco1")
    (43 "Eco2.User" user "User.Eco2")
    (44 "Edge.Cuts" user)
    (45 "Margin" user)
    (46 "B.CrtYd" user "B.Courtyard")
    (47 "F.CrtYd" user "F.Courtyard")
    (48 "B.Fab" user)
    (49 "F.Fab" user)
  )
	(footprint "antmicro-footprints:R_0402_1005Metric" (layer "F.Cu")
    (at 107 104 90)
    (descr "Resistor SMD 0402")
    (tags "resistor SMD 0402")
    (property "Author" "Antmicro")
    (property "License" "Apache-2.0")
    (property "MPN" "CR0402-FX-2201GLF")
    (property "Manufacturer" "Bourns")
    (property "Public" "False")
    (property "Sheetfile" "ethernet.kicad_sch")
    (property "Sheetname" "Ethernet")
    (property "Tolerance" "1%")
    (property "Val" "2k2")
    (property "ki_description" "SMD Chip Resistor, 2.2 kohm, ± 1%, 62.5 mW, 0402 [1005 Metric], Thick Film, General Purpose")
    (property "ki_keywords" "0402, SMT, RESISTOR, PASSIVE")
    (attr smd)
    (fp_text reference "R9" (at 0 9 90) (layer "F.SilkS")
        (effects (font (size 0.7 0.7) (thickness 0.127)))
    )
    (fp_text value "R_2k2_0402" (at 0 1.17 90) (layer "F.Fab")
        (effects (font (size 1 1) (thickness 0.15)))
    )
    (fp_text user "${REFERENCE}" (at 0 0 90) (layer "F.Fab")
        (effects (font (size 0.25 0.25) (thickness 0.04)))
    )
    (fp_text user "License: Apache-2.0" (at -0.95 5.169 90) (layer "F.Fab") hide
        (effects (font (size 0.7 0.7) (thickness 0.15)) (justify left bottom))
    )
    (fp_text user "Author: Antmicro" (at -0.95 4.169 90) (layer "F.Fab") hide
        (effects (font (size 0.7 0.7) (thickness 0.15)) (justify left bottom))
    )
    (fp_rect (start -0.925 -0.47) (end 0.925 0.47)
      (stroke (width 0.05) (type default)) (fill none) (layer "F.CrtYd"))
    (fp_rect (start -0.5 -0.25) (end 0.5 0.25)
      (stroke (width 0.15) (type solid)) (fill none) (layer "F.Fab"))
    (pad "1" smd roundrect (at -0.48 0 90) (size 0.59 0.64) (layers "F.Cu" "F.Paste" "F.Mask") (roundrect_rratio 0.25)
      (net 2 "VCC3V3") (pintype "passive"))
    (pad "2" smd roundrect (at 0.48 0 90) (size 0.59 0.64) (layers "F.Cu" "F.Paste" "F.Mask") (roundrect_rratio 0.25)
      (net 162 "ETH_MDIO") (pintype "passive"))
  )
	(footprint "antmicro-footprints:Conn_Molex_Pico-Lock_1x2_504050-0291" (layer "F.Cu")
    (at 66.27 163.64 -90)
    (property "Author" "Antmicro")
    (property "License" "Apache-2.0")
    (property "MPN" "504050-0291")
    (property "Manufacturer" "Molex")
    (property "Sheetfile" "power-supply.kicad_sch")
    (property "Sheetname" "Power supply")
    (property "ki_description" "Connector Header Surface Mount, Right Angle 2 position 0.059\" (1.50mm)")
    (property "ki_keywords" "CONNECTOR, HEADER, SMT")
    (attr smd)
    (fp_text reference "J8" (at -2.045 -3.84 -90) (layer "F.SilkS")
        (effects (font (size 0.7 0.7) (thickness 0.15)) (justify left bottom))
    )
    (fp_text value "Molex_Pico-Lock_1x2_504050-0291" (at -0.749 4.35 -90) (layer "F.Fab")
        (effects (font (size 0.7 0.7) (thickness 0.15)) (justify left bottom))
    )
    (fp_text user "License: Apache-2.0" (at -3.481 12.573 -90) (layer "F.Fab") hide
        (effects (font (size 0.7 0.7) (thickness 0.15)) (justify left bottom))
    )
    (fp_text user "${REFERENCE}" (at -3.481 10.175 -90) (layer "F.Fab") hide
        (effects (font (size 0.7 0.7) (thickness 0.15)) (justify left bottom))
    )
    (fp_text user "Author: Antmicro" (at -3.481 11.374 -90) (layer "F.Fab") hide
        (effects (font (size 0.7 0.7) (thickness 0.15)) (justify left bottom))
    )
    (fp_line (start -3.374 -2.86) (end -1.4 -2.86)
      (stroke (width 0.15) (type solid)) (layer "F.SilkS"))
    (fp_line (start -3.374 1.088) (end -3.374 -2.86)
      (stroke (width 0.15) (type solid)) (layer "F.SilkS"))
    (fp_line (start -1.639 3.239) (end -1.639 1.289)
      (stroke (width 0.15) (type solid)) (layer "F.SilkS"))
    (fp_line (start 1.399 -2.86) (end 3.374 -2.86)
      (stroke (width 0.15) (type solid)) (layer "F.SilkS"))
    (fp_line (start 1.649 1.289) (end -1.639 1.289)
      (stroke (width 0.15) (type solid)) (layer "F.SilkS"))
    (fp_line (start 1.649 1.289) (end 1.649 3.228)
      (stroke (width 0.15) (type solid)) (layer "F.SilkS"))
    (fp_line (start 3.374 -2.86) (end 3.374 1.088)
      (stroke (width 0.15) (type solid)) (layer "F.SilkS"))
    (fp_circle (center -1.249 -3.15) (end -1.199 -3.15)
      (stroke (width 0.15) (type solid)) (fill solid) (layer "F.SilkS"))
    (fp_line (start -4.249 1.18) (end -3.629 1.18)
      (stroke (width 0.05) (type solid)) (layer "F.CrtYd"))
    (fp_line (start -4.249 3.47) (end -4.249 1.18)
      (stroke (width 0.05) (type solid)) (layer "F.CrtYd"))
    (fp_line (start -3.629 -3.61) (end 3.621 -3.61)
      (stroke (width 0.05) (type solid)) (layer "F.CrtYd"))
    (fp_line (start -3.629 1.18) (end -3.629 -3.61)
      (stroke (width 0.05) (type solid)) (layer "F.CrtYd"))
    (fp_line (start 3.621 -3.61) (end 3.621 1.18)
      (stroke (width 0.05) (type solid)) (layer "F.CrtYd"))
    (fp_line (start 3.621 1.18) (end 4.231 1.18)
      (stroke (width 0.05) (type solid)) (layer "F.CrtYd"))
    (fp_line (start 4.231 1.18) (end 4.231 3.47)
      (stroke (width 0.05) (type solid)) (layer "F.CrtYd"))
    (fp_line (start 4.231 3.47) (end -4.249 3.47)
      (stroke (width 0.05) (type solid)) (layer "F.CrtYd"))
    (fp_line (start -3.374 -2.86) (end 3.374 -2.86)
      (stroke (width 0.15) (type solid)) (layer "F.Fab"))
    (fp_line (start -3.374 3.239) (end -3.374 -2.86)
      (stroke (width 0.15) (type solid)) (layer "F.Fab"))
    (fp_line (start -3.374 3.239) (end -1.749 3.239)
      (stroke (width 0.15) (type solid)) (layer "F.Fab"))
    (fp_line (start -1.749 3.249) (end -1.749 1.188)
      (stroke (width 0.15) (type solid)) (layer "F.Fab"))
    (fp_line (start 1.75 1.188) (end -1.749 1.188)
      (stroke (width 0.15) (type solid)) (layer "F.Fab"))
    (fp_line (start 1.75 1.188) (end 1.75 3.239)
      (stroke (width 0.15) (type solid)) (layer "F.Fab"))
    (fp_line (start 1.75 3.239) (end 3.374 3.239)
      (stroke (width 0.15) (type solid)) (layer "F.Fab"))
    (fp_line (start 3.374 -2.86) (end 3.374 3.239)
      (stroke (width 0.15) (type solid)) (layer "F.Fab"))
    (pad "1" smd roundrect (at -0.749 -2.85 270) (size 0.6 1) (layers "F.Cu" "F.Paste" "F.Mask") (roundrect_rratio 0.25)
      (net 57 "P12V_AUX") (pinfunction "1") (pintype "passive"))
    (pad "2" smd roundrect (at 0.75 -2.85 270) (size 0.6 1) (layers "F.Cu" "F.Paste" "F.Mask") (roundrect_rratio 0.25)
      (net 1 "GND") (pinfunction "2") (pintype "passive"))
    (pad "SH" smd roundrect (at -3.354 2.338 270) (size 1.25 1.8) (layers "F.Cu" "F.Paste" "F.Mask") (roundrect_rratio 0.25)
      (net 1 "GND") (pinfunction "SH") (pintype "passive"))
    (pad "SH" smd roundrect (at 3.356 2.338 270) (size 1.25 1.8) (layers "F.Cu" "F.Paste" "F.Mask") (roundrect_rratio 0.25)
      (net 1 "GND") (pinfunction "SH") (pintype "passive"))
  )
	(footprint "antmicro-footprints:Conn_Molex_Pico-Lock_1x2_504050-0291" (layer "F.Cu")
    (at 143 148.48 180)
    (property "Author" "Antmicro")
    (property "License" "Apache-2.0")
    (property "MPN" "504050-0291")
    (property "Manufacturer" "Molex")
    (property "Sheetfile" "power-supply.kicad_sch")
    (property "Sheetname" "Power supply")
    (property "ki_description" "Connector Header Surface Mount, Right Angle 2 position 0.059\" (1.50mm)")
    (property "ki_keywords" "CONNECTOR, HEADER, SMT")
    (attr smd)
    (fp_text reference "J18" (at -1.17 -4.025 180) (layer "F.SilkS")
        (effects (font (size 0.7 0.7) (thickness 0.15)) (justify left bottom))
    )
    (fp_text value "Molex_Pico-Lock_1x2_504050-0291" (at -0.749 4.35 180) (layer "F.Fab")
        (effects (font (size 0.7 0.7) (thickness 0.15)) (justify left bottom))
    )
    (fp_text user "Author: Antmicro" (at -3.481 11.374 180) (layer "F.Fab") hide
        (effects (font (size 0.7 0.7) (thickness 0.15)) (justify left bottom))
    )
    (fp_text user "License: Apache-2.0" (at -3.481 12.573 180) (layer "F.Fab") hide
        (effects (font (size 0.7 0.7) (thickness 0.15)) (justify left bottom))
    )
    (fp_text user "${REFERENCE}" (at -3.481 10.175 180) (layer "F.Fab") hide
        (effects (font (size 0.7 0.7) (thickness 0.15)) (justify left bottom))
    )
    (fp_line (start -3.374 -2.86) (end -1.4 -2.86)
      (stroke (width 0.15) (type solid)) (layer "F.SilkS"))
    (fp_line (start -3.374 1.088) (end -3.374 -2.86)
      (stroke (width 0.15) (type solid)) (layer "F.SilkS"))
    (fp_line (start -1.639 3.239) (end -1.639 1.289)
      (stroke (width 0.15) (type solid)) (layer "F.SilkS"))
    (fp_line (start 1.399 -2.86) (end 3.374 -2.86)
      (stroke (width 0.15) (type solid)) (layer "F.SilkS"))
    (fp_line (start 1.649 1.289) (end -1.639 1.289)
      (stroke (width 0.15) (type solid)) (layer "F.SilkS"))
    (fp_line (start 1.649 1.289) (end 1.649 3.228)
      (stroke (width 0.15) (type solid)) (layer "F.SilkS"))
    (fp_line (start 3.374 -2.86) (end 3.374 1.088)
      (stroke (width 0.15) (type solid)) (layer "F.SilkS"))
    (fp_circle (center -1.249 -3.15) (end -1.199 -3.15)
      (stroke (width 0.15) (type solid)) (fill solid) (layer "F.SilkS"))
    (fp_line (start -4.249 1.18) (end -3.629 1.18)
      (stroke (width 0.05) (type solid)) (layer "F.CrtYd"))
    (fp_line (start -4.249 3.47) (end -4.249 1.18)
      (stroke (width 0.05) (type solid)) (layer "F.CrtYd"))
    (fp_line (start -3.629 -3.61) (end 3.621 -3.61)
      (stroke (width 0.05) (type solid)) (layer "F.CrtYd"))
    (fp_line (start -3.629 1.18) (end -3.629 -3.61)
      (stroke (width 0.05) (type solid)) (layer "F.CrtYd"))
    (fp_line (start 3.621 -3.61) (end 3.621 1.18)
      (stroke (width 0.05) (type solid)) (layer "F.CrtYd"))
    (fp_line (start 3.621 1.18) (end 4.231 1.18)
      (stroke (width 0.05) (type solid)) (layer "F.CrtYd"))
    (fp_line (start 4.231 1.18) (end 4.231 3.47)
      (stroke (width 0.05) (type solid)) (layer "F.CrtYd"))
    (fp_line (start 4.231 3.47) (end -4.249 3.47)
      (stroke (width 0.05) (type solid)) (layer "F.CrtYd"))
    (fp_line (start -3.374 -2.86) (end 3.374 -2.86)
      (stroke (width 0.15) (type solid)) (layer "F.Fab"))
    (fp_line (start -3.374 3.239) (end -3.374 -2.86)
      (stroke (width 0.15) (type solid)) (layer "F.Fab"))
    (fp_line (start -3.374 3.239) (end -1.749 3.239)
      (stroke (width 0.15) (type solid)) (layer "F.Fab"))
    (fp_line (start -1.749 3.249) (end -1.749 1.188)
      (stroke (width 0.15) (type solid)) (layer "F.Fab"))
    (fp_line (start 1.75 1.188) (end -1.749 1.188)
      (stroke (width 0.15) (type solid)) (layer "F.Fab"))
    (fp_line (start 1.75 1.188) (end 1.75 3.239)
      (stroke (width 0.15) (type solid)) (layer "F.Fab"))
    (fp_line (start 1.75 3.239) (end 3.374 3.239)
      (stroke (width 0.15) (type solid)) (layer "F.Fab"))
    (fp_line (start 3.374 -2.86) (end 3.374 3.239)
      (stroke (width 0.15) (type solid)) (layer "F.Fab"))
    (pad "1" smd roundrect (at -0.749 -2.85 180) (size 0.6 1) (layers "F.Cu" "F.Paste" "F.Mask") (roundrect_rratio 0.25)
      (net 414 "3V0_BAT") (pinfunction "1") (pintype "passive"))
    (pad "2" smd roundrect (at 0.75 -2.85 180) (size 0.6 1) (layers "F.Cu" "F.Paste" "F.Mask") (roundrect_rratio 0.25)
      (net 1 "GND") (pinfunction "2") (pintype "passive"))
    (pad "SH" smd roundrect (at -3.354 2.338 180) (size 1.25 1.8) (layers "F.Cu" "F.Paste" "F.Mask") (roundrect_rratio 0.25)
      (net 1 "GND") (pinfunction "SH") (pintype "passive"))
    (pad "SH" smd roundrect (at 3.356 2.338 180) (size 1.25 1.8) (layers "F.Cu" "F.Paste" "F.Mask") (roundrect_rratio 0.25)
      (net 1 "GND") (pinfunction "SH") (pintype "passive"))
  )
	(footprint "antmicro-footprints:Oscillator_SMD_Abracon_ASEMB_3.2x2.5mm" (layer "F.Cu")
    (at 130.54 117.1 180)
    (property "Author" "Antmicro")
    (property "License" "Apache-2.0")
    (property "MPN" "ASEMB-24.000MHZ-LC-T")
    (property "Manufacturer" "Abracon")
    (property "Public" "False")
    (property "Sheetfile" "interfaces.kicad_sch")
    (property "Sheetname" "Interfaces")
    (property "Val" "24 MHz")
    (property "ki_description" "MEMS Oscillator, Clock, Pure Silicon&trade;, 24 MHz, SMD, 3.2mm x 2.5mm, 50 ppm, 3.3 V, ASEMB, LVCMOS")
    (property "ki_keywords" "OSCILLATOR, MEMS")
    (attr smd)
    (fp_text reference "Y2" (at -2.84 -0.675 270) (layer "F.SilkS")
        (effects (font (size 0.7 0.7) (thickness 0.15)) (justify left bottom))
    )
    (fp_text value "Oscillator_24MHz_ASEMB" (at -10.2616 2.8956 180) (layer "F.Fab")
        (effects (font (size 0.7 0.7) (thickness 0.15)) (justify left bottom))
    )
    (fp_text user "." (at -1.651 -2 180) (layer "F.SilkS") hide
        (effects (font (size 0.7 0.7) (thickness 0.15)) (justify left bottom))
    )
    (fp_text user "${REFERENCE}" (at -10.2616 4.8956 180) (layer "F.Fab") hide
        (effects (font (size 0.7 0.7) (thickness 0.15)) (justify left bottom))
    )
    (fp_text user "Author: Antmicro" (at -10.2616 7.2956 180) (layer "F.Fab") hide
        (effects (font (size 0.7 0.7) (thickness 0.15)) (justify left bottom))
    )
    (fp_text user "License: Apache-2.0" (at -10.2616 6.0956 180) (layer "F.Fab") hide
        (effects (font (size 0.7 0.7) (thickness 0.15)) (justify left bottom))
    )
    (fp_circle (center -1.5748 -1.8034) (end -1.5248 -1.8034)
      (stroke (width 0.15) (type solid)) (fill solid) (layer "F.SilkS"))
    (fp_rect (start -1.752 -2.101) (end 1.749 2.1)
      (stroke (width 0.05) (type solid)) (fill none) (layer "F.CrtYd"))
    (fp_line (start -1.2192 -1.4224) (end -1.0668 -1.5748)
      (stroke (width 0.15) (type solid)) (layer "F.Fab"))
    (fp_rect (start -1.252 -1.601) (end 1.249 1.6)
      (stroke (width 0.15) (type solid)) (fill none) (layer "F.Fab"))
    (pad "1" smd rect (at -0.951 -1.049 180) (size 1 0.9) (layers "F.Cu" "F.Paste" "F.Mask")
      (net 2 "VCC3V3") (pinfunction "EN") (pintype "input"))
    (pad "2" smd rect (at -0.951 1.05 180) (size 1 0.9) (layers "F.Cu" "F.Paste" "F.Mask")
      (net 1 "GND") (pinfunction "GND") (pintype "power_in"))
    (pad "3" smd rect (at 0.948 1.05 180) (size 1 0.9) (layers "F.Cu" "F.Paste" "F.Mask")
      (net 679 "/Interfaces/USB1_CLK") (pinfunction "OUT") (pintype "output"))
    (pad "4" smd rect (at 0.948 -1.049 180) (size 1 0.9) (layers "F.Cu" "F.Paste" "F.Mask")
      (net 2 "VCC3V3") (pinfunction "VDD") (pintype "power_in"))
  )
	(footprint "antmicro-footprints:Oscillator_SMD_Abracon_ASEMB_3.2x2.5mm" (layer "F.Cu")
    (at 125.64 133.18 180)
    (property "Author" "Antmicro")
    (property "License" "Apache-2.0")
    (property "MPN" "ASEMB-24.000MHZ-LC-T")
    (property "Manufacturer" "Abracon")
    (property "Public" "False")
    (property "Sheetfile" "interfaces.kicad_sch")
    (property "Sheetname" "Interfaces")
    (property "Val" "24 MHz")
    (property "ki_description" "MEMS Oscillator, Clock, Pure Silicon&trade;, 24 MHz, SMD, 3.2mm x 2.5mm, 50 ppm, 3.3 V, ASEMB, LVCMOS")
    (property "ki_keywords" "OSCILLATOR, MEMS")
    (attr smd)
    (fp_text reference "Y3" (at 1.86 -0.535 90) (layer "F.SilkS")
        (effects (font (size 0.7 0.7) (thickness 0.15)) (justify left bottom))
    )
    (fp_text value "Oscillator_24MHz_ASEMB" (at -10.2616 2.8956 180) (layer "F.Fab")
        (effects (font (size 0.7 0.7) (thickness 0.15)) (justify left bottom))
    )
    (fp_text user "." (at -1.651 -2 180) (layer "F.SilkS") hide
        (effects (font (size 0.7 0.7) (thickness 0.15)) (justify left bottom))
    )
    (fp_text user "Author: Antmicro" (at -10.2616 7.2956 180) (layer "F.Fab") hide
        (effects (font (size 0.7 0.7) (thickness 0.15)) (justify left bottom))
    )
    (fp_text user "License: Apache-2.0" (at -10.2616 6.0956 180) (layer "F.Fab") hide
        (effects (font (size 0.7 0.7) (thickness 0.15)) (justify left bottom))
    )
    (fp_text user "${REFERENCE}" (at -10.2616 4.8956 180) (layer "F.Fab") hide
        (effects (font (size 0.7 0.7) (thickness 0.15)) (justify left bottom))
    )
    (fp_circle (center -1.5748 -1.8034) (end -1.5248 -1.8034)
      (stroke (width 0.15) (type solid)) (fill solid) (layer "F.SilkS"))
    (fp_rect (start -1.752 -2.101) (end 1.749 2.1)
      (stroke (width 0.05) (type solid)) (fill none) (layer "F.CrtYd"))
    (fp_line (start -1.2192 -1.4224) (end -1.0668 -1.5748)
      (stroke (width 0.15) (type solid)) (layer "F.Fab"))
    (fp_rect (start -1.252 -1.601) (end 1.249 1.6)
      (stroke (width 0.15) (type solid)) (fill none) (layer "F.Fab"))
    (pad "1" smd rect (at -0.951 -1.049 180) (size 1 0.9) (layers "F.Cu" "F.Paste" "F.Mask")
      (net 2 "VCC3V3") (pinfunction "EN") (pintype "input"))
    (pad "2" smd rect (at -0.951 1.05 180) (size 1 0.9) (layers "F.Cu" "F.Paste" "F.Mask")
      (net 1 "GND") (pinfunction "GND") (pintype "power_in"))
    (pad "3" smd rect (at 0.948 1.05 180) (size 1 0.9) (layers "F.Cu" "F.Paste" "F.Mask")
      (net 678 "/Interfaces/USB2_CLK") (pinfunction "OUT") (pintype "output"))
    (pad "4" smd rect (at 0.948 -1.049 180) (size 1 0.9) (layers "F.Cu" "F.Paste" "F.Mask")
      (net 2 "VCC3V3") (pinfunction "VDD") (pintype "power_in"))
  )
)
